(kicad_pcb
	(version 20260206)
	(generator "pcbnew")
	(generator_version "10.0")
	(general
		(thickness 1.6)
		(legacy_teardrops no)
	)
	(paper "A4")
	(title_block
		(title "03242023_DA0F0TMBIJ0_F0T_Motherboard_J_brd_V01_OCP.brd")
		(comment 1 "Grand Teton / footprints 2745-2751 of 6105")
	)
	(layers
		(0 "F.Cu" signal "TOP")
		(4 "In1.Cu" signal "GND")
		(6 "In2.Cu" signal "IN1")
		(8 "In3.Cu" signal "GND1")
		(10 "In4.Cu" signal "IN2")
		(12 "In5.Cu" signal "GND2")
		(14 "In6.Cu" signal "IN3")
		(16 "In7.Cu" signal "GND3")
		(18 "In8.Cu" signal "VCC")
		(20 "In9.Cu" signal "VCC1")
		(22 "In10.Cu" signal "GND4")
		(24 "In11.Cu" signal "IN4")
		(26 "In12.Cu" signal "GND5")
		(28 "In13.Cu" signal "IN5")
		(30 "In14.Cu" signal "GND6")
		(32 "In15.Cu" signal "IN6")
		(34 "In16.Cu" signal "GND7")
		(2 "B.Cu" signal "BOTTOM")
		(9 "F.Adhes" user "F.Adhesive")
		(11 "B.Adhes" user "B.Adhesive")
		(13 "F.Paste" user "Package Geometry/Pastemask Top")
		(15 "B.Paste" user "Package Geometry/Pastemask Bottom")
		(5 "F.SilkS" user "Ref Des/Silkscreen Top")
		(7 "B.SilkS" user "Ref Des/Silkscreen Bottom")
		(1 "F.Mask" user "Board Geometry/Soldermask Top")
		(3 "B.Mask" user "Board Geometry/Soldermask Bottom")
		(17 "Dwgs.User" user "User.Drawings")
		(19 "Cmts.User" user "User.Comments")
		(21 "Eco1.User" user "User.Eco1")
		(23 "Eco2.User" user "User.Eco2")
		(25 "Edge.Cuts" user "Board Geometry/Outline")
		(27 "Margin" user)
		(31 "F.CrtYd" user "Package Geometry/Place Bound Top")
		(29 "B.CrtYd" user "Package Geometry/Place Bound Bottom")
		(35 "F.Fab" user "Ref Des/Assembly Top")
		(33 "B.Fab" user "Ref Des/Assembly Bottom")
	)
	(footprint ""
		(layer "F.Cu")
		(at 28.190698 -137.97661 90)
		(property "Reference" "PR4246"
			(at 0 0 90)
			(layer "F.SilkS")
			(hide yes)
			(effects
				(font
					(size 1.27 1.27)
				)
			)
		)
		(property "Value" ""
			(at 0 0 90)
			(layer "F.Fab")
			(effects
				(font
					(size 1.27 1.27)
				)
			)
		)
		(duplicate_pad_numbers_are_jumpers no)
		(fp_line
			(start 0.7874 -0.4064)
			(end 0.7874 0.4064)
			(stroke
				(width 0.1524)
				(type default)
			)
			(layer "F.SilkS")
		)
		(fp_line
			(start -0.7874 -0.4064)
			(end 0.7874 -0.4064)
			(stroke
				(width 0.1524)
				(type default)
			)
			(layer "F.SilkS")
		)
		(fp_line
			(start 0.7874 0.4064)
			(end -0.7874 0.4064)
			(stroke
				(width 0.1524)
				(type default)
			)
			(layer "F.SilkS")
		)
		(fp_line
			(start -0.7874 0.4064)
			(end -0.7874 -0.4064)
			(stroke
				(width 0.1524)
				(type default)
			)
			(layer "F.SilkS")
		)
		(fp_line
			(start -0.12065 -0.305054)
			(end -0.12065 -0.2794)
			(stroke
				(width 0.1)
				(type default)
			)
			(layer "F.Fab")
		)
		(fp_line
			(start -0.67945 -0.305054)
			(end -0.12065 -0.305054)
			(stroke
				(width 0.1)
				(type default)
			)
			(layer "F.Fab")
		)
		(fp_line
			(start 0.67945 -0.3048)
			(end 0.67945 0.3048)
			(stroke
				(width 0.1)
				(type default)
			)
			(layer "F.Fab")
		)
		(fp_line
			(start 0.12065 -0.3048)
			(end 0.67945 -0.3048)
			(stroke
				(width 0.1)
				(type default)
			)
			(layer "F.Fab")
		)
		(fp_line
			(start 0.12065 -0.2794)
			(end 0.12065 -0.3048)
			(stroke
				(width 0.1)
				(type default)
			)
			(layer "F.Fab")
		)
		(fp_line
			(start -0.12065 -0.2794)
			(end 0.12065 -0.2794)
			(stroke
				(width 0.1)
				(type default)
			)
			(layer "F.Fab")
		)
		(fp_line
			(start 0.120396 0.2794)
			(end -0.12065 0.2794)
			(stroke
				(width 0.1)
				(type default)
			)
			(layer "F.Fab")
		)
		(fp_line
			(start -0.12065 0.2794)
			(end -0.12065 0.3048)
			(stroke
				(width 0.1)
				(type default)
			)
			(layer "F.Fab")
		)
		(fp_line
			(start 0.67945 0.3048)
			(end 0.120396 0.3048)
			(stroke
				(width 0.1)
				(type default)
			)
			(layer "F.Fab")
		)
		(fp_line
			(start 0.120396 0.3048)
			(end 0.120396 0.2794)
			(stroke
				(width 0.1)
				(type default)
			)
			(layer "F.Fab")
		)
		(fp_line
			(start -0.12065 0.3048)
			(end -0.67945 0.3048)
			(stroke
				(width 0.1)
				(type default)
			)
			(layer "F.Fab")
		)
		(fp_line
			(start -0.67945 0.3048)
			(end -0.67945 -0.305054)
			(stroke
				(width 0.1)
				(type default)
			)
			(layer "F.Fab")
		)
		(pad "1" smd circle
			(at -0.40005 0 90)
			(size 0 0)
			(layers "F.Cu" "F.Mask" "F.Paste")
			(net "NC_PVCCINFAON_CPU1_ACSP7")
		)
		(pad "2" smd circle
			(at 0.40005 0 90)
			(size 0 0)
			(layers "F.Cu" "F.Mask" "F.Paste")
			(net "GND")
		)
	)
	(footprint ""
		(layer "F.Cu")
		(at 170.23588 -440.019948)
		(property "Reference" "R3454"
			(at 0 0 0)
			(layer "F.SilkS")
			(hide yes)
			(effects
				(font
					(size 1.27 1.27)
				)
			)
		)
		(property "Value" ""
			(at 0 0 0)
			(layer "F.Fab")
			(effects
				(font
					(size 1.27 1.27)
				)
			)
		)
		(duplicate_pad_numbers_are_jumpers no)
		(fp_line
			(start -0.7874 -0.4064)
			(end 0.7874 -0.4064)
			(stroke
				(width 0.1524)
				(type default)
			)
			(layer "F.SilkS")
		)
		(fp_line
			(start -0.7874 0.4064)
			(end -0.7874 -0.4064)
			(stroke
				(width 0.1524)
				(type default)
			)
			(layer "F.SilkS")
		)
		(fp_line
			(start 0.7874 -0.4064)
			(end 0.7874 0.4064)
			(stroke
				(width 0.1524)
				(type default)
			)
			(layer "F.SilkS")
		)
		(fp_line
			(start 0.7874 0.4064)
			(end -0.7874 0.4064)
			(stroke
				(width 0.1524)
				(type default)
			)
			(layer "F.SilkS")
		)
		(fp_line
			(start -0.67945 -0.305054)
			(end -0.12065 -0.305054)
			(stroke
				(width 0.1)
				(type default)
			)
			(layer "F.Fab")
		)
		(fp_line
			(start -0.67945 0.3048)
			(end -0.67945 -0.305054)
			(stroke
				(width 0.1)
				(type default)
			)
			(layer "F.Fab")
		)
		(fp_line
			(start -0.12065 -0.305054)
			(end -0.12065 -0.2794)
			(stroke
				(width 0.1)
				(type default)
			)
			(layer "F.Fab")
		)
		(fp_line
			(start -0.12065 -0.2794)
			(end 0.12065 -0.2794)
			(stroke
				(width 0.1)
				(type default)
			)
			(layer "F.Fab")
		)
		(fp_line
			(start -0.12065 0.2794)
			(end -0.12065 0.3048)
			(stroke
				(width 0.1)
				(type default)
			)
			(layer "F.Fab")
		)
		(fp_line
			(start -0.12065 0.3048)
			(end -0.67945 0.3048)
			(stroke
				(width 0.1)
				(type default)
			)
			(layer "F.Fab")
		)
		(fp_line
			(start 0.120396 0.2794)
			(end -0.12065 0.2794)
			(stroke
				(width 0.1)
				(type default)
			)
			(layer "F.Fab")
		)
		(fp_line
			(start 0.120396 0.3048)
			(end 0.120396 0.2794)
			(stroke
				(width 0.1)
				(type default)
			)
			(layer "F.Fab")
		)
		(fp_line
			(start 0.12065 -0.3048)
			(end 0.67945 -0.3048)
			(stroke
				(width 0.1)
				(type default)
			)
			(layer "F.Fab")
		)
		(fp_line
			(start 0.12065 -0.2794)
			(end 0.12065 -0.3048)
			(stroke
				(width 0.1)
				(type default)
			)
			(layer "F.Fab")
		)
		(fp_line
			(start 0.67945 -0.3048)
			(end 0.67945 0.3048)
			(stroke
				(width 0.1)
				(type default)
			)
			(layer "F.Fab")
		)
		(fp_line
			(start 0.67945 0.3048)
			(end 0.120396 0.3048)
			(stroke
				(width 0.1)
				(type default)
			)
			(layer "F.Fab")
		)
		(pad "1" smd circle
			(at -0.40005 0)
			(size 0 0)
			(layers "F.Cu" "F.Mask" "F.Paste")
			(net "GPU_FPGA_BOOT_EN_BUF_R")
		)
		(pad "2" smd circle
			(at 0.40005 0)
			(size 0 0)
			(layers "F.Cu" "F.Mask" "F.Paste")
			(net "GND")
		)
	)
	(footprint ""
		(layer "F.Cu")
		(at 92.40647 -337.214718 -90)
		(property "Reference" "PC507_P1_6"
			(at 0 0 270)
			(layer "F.SilkS")
			(hide yes)
			(effects
				(font
					(size 1.27 1.27)
				)
			)
		)
		(property "Value" ""
			(at 0 0 270)
			(layer "F.Fab")
			(effects
				(font
					(size 1.27 1.27)
				)
			)
		)
		(duplicate_pad_numbers_are_jumpers no)
		(fp_line
			(start -0.7874 0.4064)
			(end -0.7874 -0.4064)
			(stroke
				(width 0.1524)
				(type default)
			)
			(layer "F.SilkS")
		)
		(fp_line
			(start 0.7874 0.4064)
			(end -0.7874 0.4064)
			(stroke
				(width 0.1524)
				(type default)
			)
			(layer "F.SilkS")
		)
		(fp_line
			(start -0.7874 -0.4064)
			(end 0.7874 -0.4064)
			(stroke
				(width 0.1524)
				(type default)
			)
			(layer "F.SilkS")
		)
		(fp_line
			(start 0.7874 -0.4064)
			(end 0.7874 0.4064)
			(stroke
				(width 0.1524)
				(type default)
			)
			(layer "F.SilkS")
		)
		(fp_line
			(start -0.67945 0.3048)
			(end -0.67945 -0.305054)
			(stroke
				(width 0.1)
				(type default)
			)
			(layer "F.Fab")
		)
		(fp_line
			(start -0.12065 0.3048)
			(end -0.67945 0.3048)
			(stroke
				(width 0.1)
				(type default)
			)
			(layer "F.Fab")
		)
		(fp_line
			(start 0.120396 0.3048)
			(end 0.120396 0.2794)
			(stroke
				(width 0.1)
				(type default)
			)
			(layer "F.Fab")
		)
		(fp_line
			(start 0.67945 0.3048)
			(end 0.120396 0.3048)
			(stroke
				(width 0.1)
				(type default)
			)
			(layer "F.Fab")
		)
		(fp_line
			(start -0.12065 0.2794)
			(end -0.12065 0.3048)
			(stroke
				(width 0.1)
				(type default)
			)
			(layer "F.Fab")
		)
		(fp_line
			(start 0.120396 0.2794)
			(end -0.12065 0.2794)
			(stroke
				(width 0.1)
				(type default)
			)
			(layer "F.Fab")
		)
		(fp_line
			(start -0.12065 -0.2794)
			(end 0.12065 -0.2794)
			(stroke
				(width 0.1)
				(type default)
			)
			(layer "F.Fab")
		)
		(fp_line
			(start 0.12065 -0.2794)
			(end 0.12065 -0.3048)
			(stroke
				(width 0.1)
				(type default)
			)
			(layer "F.Fab")
		)
		(fp_line
			(start 0.12065 -0.3048)
			(end 0.67945 -0.3048)
			(stroke
				(width 0.1)
				(type default)
			)
			(layer "F.Fab")
		)
		(fp_line
			(start 0.67945 -0.3048)
			(end 0.67945 0.3048)
			(stroke
				(width 0.1)
				(type default)
			)
			(layer "F.Fab")
		)
		(fp_line
			(start -0.67945 -0.305054)
			(end -0.12065 -0.305054)
			(stroke
				(width 0.1)
				(type default)
			)
			(layer "F.Fab")
		)
		(fp_line
			(start -0.12065 -0.305054)
			(end -0.12065 -0.2794)
			(stroke
				(width 0.1)
				(type default)
			)
			(layer "F.Fab")
		)
		(pad "1" smd circle
			(at -0.40005 0 270)
			(size 0 0)
			(layers "F.Cu" "F.Mask" "F.Paste")
			(net "SW_P12V_PVCCIN_CPU1_FLT")
		)
		(pad "2" smd circle
			(at 0.40005 0 270)
			(size 0 0)
			(layers "F.Cu" "F.Mask" "F.Paste")
			(net "GND")
		)
	)
	(footprint ""
		(layer "F.Cu")
		(at 118.542816 -244.032024 90)
		(property "Reference" "C224"
			(at 0 0 90)
			(layer "F.SilkS")
			(hide yes)
			(effects
				(font
					(size 1.27 1.27)
				)
			)
		)
		(property "Value" ""
			(at 0 0 90)
			(layer "F.Fab")
			(effects
				(font
					(size 1.27 1.27)
				)
			)
		)
		(duplicate_pad_numbers_are_jumpers no)
		(fp_line
			(start 0.7874 -0.4064)
			(end 0.7874 0.4064)
			(stroke
				(width 0.1524)
				(type default)
			)
			(layer "F.SilkS")
		)
		(fp_line
			(start -0.7874 -0.4064)
			(end 0.7874 -0.4064)
			(stroke
				(width 0.1524)
				(type default)
			)
			(layer "F.SilkS")
		)
		(fp_line
			(start 0.7874 0.4064)
			(end -0.7874 0.4064)
			(stroke
				(width 0.1524)
				(type default)
			)
			(layer "F.SilkS")
		)
		(fp_line
			(start -0.7874 0.4064)
			(end -0.7874 -0.4064)
			(stroke
				(width 0.1524)
				(type default)
			)
			(layer "F.SilkS")
		)
		(fp_line
			(start -0.12065 -0.305054)
			(end -0.12065 -0.2794)
			(stroke
				(width 0.1)
				(type default)
			)
			(layer "F.Fab")
		)
		(fp_line
			(start -0.67945 -0.305054)
			(end -0.12065 -0.305054)
			(stroke
				(width 0.1)
				(type default)
			)
			(layer "F.Fab")
		)
		(fp_line
			(start 0.67945 -0.3048)
			(end 0.67945 0.3048)
			(stroke
				(width 0.1)
				(type default)
			)
			(layer "F.Fab")
		)
		(fp_line
			(start 0.12065 -0.3048)
			(end 0.67945 -0.3048)
			(stroke
				(width 0.1)
				(type default)
			)
			(layer "F.Fab")
		)
		(fp_line
			(start 0.12065 -0.2794)
			(end 0.12065 -0.3048)
			(stroke
				(width 0.1)
				(type default)
			)
			(layer "F.Fab")
		)
		(fp_line
			(start -0.12065 -0.2794)
			(end 0.12065 -0.2794)
			(stroke
				(width 0.1)
				(type default)
			)
			(layer "F.Fab")
		)
		(fp_line
			(start 0.120396 0.2794)
			(end -0.12065 0.2794)
			(stroke
				(width 0.1)
				(type default)
			)
			(layer "F.Fab")
		)
		(fp_line
			(start -0.12065 0.2794)
			(end -0.12065 0.3048)
			(stroke
				(width 0.1)
				(type default)
			)
			(layer "F.Fab")
		)
		(fp_line
			(start 0.67945 0.3048)
			(end 0.120396 0.3048)
			(stroke
				(width 0.1)
				(type default)
			)
			(layer "F.Fab")
		)
		(fp_line
			(start 0.120396 0.3048)
			(end 0.120396 0.2794)
			(stroke
				(width 0.1)
				(type default)
			)
			(layer "F.Fab")
		)
		(fp_line
			(start -0.12065 0.3048)
			(end -0.67945 0.3048)
			(stroke
				(width 0.1)
				(type default)
			)
			(layer "F.Fab")
		)
		(fp_line
			(start -0.67945 0.3048)
			(end -0.67945 -0.305054)
			(stroke
				(width 0.1)
				(type default)
			)
			(layer "F.Fab")
		)
		(pad "1" smd circle
			(at -0.40005 0 90)
			(size 0 0)
			(layers "F.Cu" "F.Mask" "F.Paste")
			(net "PVCCIN_CPU1")
		)
		(pad "2" smd circle
			(at 0.40005 0 90)
			(size 0 0)
			(layers "F.Cu" "F.Mask" "F.Paste")
			(net "GND")
		)
	)
	(footprint ""
		(layer "F.Cu")
		(at 112.492282 -406.439116 180)
		(property "Reference" "C1979"
			(at 0 0 180)
			(layer "F.SilkS")
			(hide yes)
			(effects
				(font
					(size 1.27 1.27)
				)
			)
		)
		(property "Value" ""
			(at 0 0 180)
			(layer "F.Fab")
			(effects
				(font
					(size 1.27 1.27)
				)
			)
		)
		(duplicate_pad_numbers_are_jumpers no)
		(fp_line
			(start 0.7874 0.4064)
			(end -0.7874 0.4064)
			(stroke
				(width 0.1524)
				(type default)
			)
			(layer "F.SilkS")
		)
		(fp_line
			(start 0.7874 -0.4064)
			(end 0.7874 0.4064)
			(stroke
				(width 0.1524)
				(type default)
			)
			(layer "F.SilkS")
		)
		(fp_line
			(start -0.7874 0.4064)
			(end -0.7874 -0.4064)
			(stroke
				(width 0.1524)
				(type default)
			)
			(layer "F.SilkS")
		)
		(fp_line
			(start -0.7874 -0.4064)
			(end 0.7874 -0.4064)
			(stroke
				(width 0.1524)
				(type default)
			)
			(layer "F.SilkS")
		)
		(fp_line
			(start 0.67945 0.3048)
			(end 0.120396 0.3048)
			(stroke
				(width 0.1)
				(type default)
			)
			(layer "F.Fab")
		)
		(fp_line
			(start 0.67945 -0.3048)
			(end 0.67945 0.3048)
			(stroke
				(width 0.1)
				(type default)
			)
			(layer "F.Fab")
		)
		(fp_line
			(start 0.12065 -0.2794)
			(end 0.12065 -0.3048)
			(stroke
				(width 0.1)
				(type default)
			)
			(layer "F.Fab")
		)
		(fp_line
			(start 0.12065 -0.3048)
			(end 0.67945 -0.3048)
			(stroke
				(width 0.1)
				(type default)
			)
			(layer "F.Fab")
		)
		(fp_line
			(start 0.120396 0.3048)
			(end 0.120396 0.2794)
			(stroke
				(width 0.1)
				(type default)
			)
			(layer "F.Fab")
		)
		(fp_line
			(start 0.120396 0.2794)
			(end -0.12065 0.2794)
			(stroke
				(width 0.1)
				(type default)
			)
			(layer "F.Fab")
		)
		(fp_line
			(start -0.12065 0.3048)
			(end -0.67945 0.3048)
			(stroke
				(width 0.1)
				(type default)
			)
			(layer "F.Fab")
		)
		(fp_line
			(start -0.12065 0.2794)
			(end -0.12065 0.3048)
			(stroke
				(width 0.1)
				(type default)
			)
			(layer "F.Fab")
		)
		(fp_line
			(start -0.12065 -0.2794)
			(end 0.12065 -0.2794)
			(stroke
				(width 0.1)
				(type default)
			)
			(layer "F.Fab")
		)
		(fp_line
			(start -0.12065 -0.305054)
			(end -0.12065 -0.2794)
			(stroke
				(width 0.1)
				(type default)
			)
			(layer "F.Fab")
		)
		(fp_line
			(start -0.67945 0.3048)
			(end -0.67945 -0.305054)
			(stroke
				(width 0.1)
				(type default)
			)
			(layer "F.Fab")
		)
		(fp_line
			(start -0.67945 -0.305054)
			(end -0.12065 -0.305054)
			(stroke
				(width 0.1)
				(type default)
			)
			(layer "F.Fab")
		)
		(pad "1" smd circle
			(at -0.40005 0 180)
			(size 0 0)
			(layers "F.Cu" "F.Mask" "F.Paste")
			(net "P3V3_AUX")
		)
		(pad "2" smd circle
			(at 0.40005 0 180)
			(size 0 0)
			(layers "F.Cu" "F.Mask" "F.Paste")
			(net "GND")
		)
	)
	(footprint ""
		(layer "F.Cu")
		(at 325.95312 -347.541342 -90)
		(property "Reference" "PC1345"
			(at 0 0 270)
			(layer "F.SilkS")
			(hide yes)
			(effects
				(font
					(size 1.27 1.27)
				)
			)
		)
		(property "Value" ""
			(at 0 0 270)
			(layer "F.Fab")
			(effects
				(font
					(size 1.27 1.27)
				)
			)
		)
		(duplicate_pad_numbers_are_jumpers no)
		(fp_line
			(start -0.7874 0.4064)
			(end -0.7874 -0.4064)
			(stroke
				(width 0.1524)
				(type default)
			)
			(layer "F.SilkS")
		)
		(fp_line
			(start 0.7874 0.4064)
			(end -0.7874 0.4064)
			(stroke
				(width 0.1524)
				(type default)
			)
			(layer "F.SilkS")
		)
		(fp_line
			(start -0.7874 -0.4064)
			(end 0.7874 -0.4064)
			(stroke
				(width 0.1524)
				(type default)
			)
			(layer "F.SilkS")
		)
		(fp_line
			(start 0.7874 -0.4064)
			(end 0.7874 0.4064)
			(stroke
				(width 0.1524)
				(type default)
			)
			(layer "F.SilkS")
		)
		(fp_line
			(start -0.67945 0.3048)
			(end -0.67945 -0.305054)
			(stroke
				(width 0.1)
				(type default)
			)
			(layer "F.Fab")
		)
		(fp_line
			(start -0.12065 0.3048)
			(end -0.67945 0.3048)
			(stroke
				(width 0.1)
				(type default)
			)
			(layer "F.Fab")
		)
		(fp_line
			(start 0.120396 0.3048)
			(end 0.120396 0.2794)
			(stroke
				(width 0.1)
				(type default)
			)
			(layer "F.Fab")
		)
		(fp_line
			(start 0.67945 0.3048)
			(end 0.120396 0.3048)
			(stroke
				(width 0.1)
				(type default)
			)
			(layer "F.Fab")
		)
		(fp_line
			(start -0.12065 0.2794)
			(end -0.12065 0.3048)
			(stroke
				(width 0.1)
				(type default)
			)
			(layer "F.Fab")
		)
		(fp_line
			(start 0.120396 0.2794)
			(end -0.12065 0.2794)
			(stroke
				(width 0.1)
				(type default)
			)
			(layer "F.Fab")
		)
		(fp_line
			(start -0.12065 -0.2794)
			(end 0.12065 -0.2794)
			(stroke
				(width 0.1)
				(type default)
			)
			(layer "F.Fab")
		)
		(fp_line
			(start 0.12065 -0.2794)
			(end 0.12065 -0.3048)
			(stroke
				(width 0.1)
				(type default)
			)
			(layer "F.Fab")
		)
		(fp_line
			(start 0.12065 -0.3048)
			(end 0.67945 -0.3048)
			(stroke
				(width 0.1)
				(type default)
			)
			(layer "F.Fab")
		)
		(fp_line
			(start 0.67945 -0.3048)
			(end 0.67945 0.3048)
			(stroke
				(width 0.1)
				(type default)
			)
			(layer "F.Fab")
		)
		(fp_line
			(start -0.67945 -0.305054)
			(end -0.12065 -0.305054)
			(stroke
				(width 0.1)
				(type default)
			)
			(layer "F.Fab")
		)
		(fp_line
			(start -0.12065 -0.305054)
			(end -0.12065 -0.2794)
			(stroke
				(width 0.1)
				(type default)
			)
			(layer "F.Fab")
		)
		(pad "1" smd circle
			(at -0.40005 0 270)
			(size 0 0)
			(layers "F.Cu" "F.Mask" "F.Paste")
			(net "GND")
		)
		(pad "2" smd circle
			(at 0.40005 0 270)
			(size 0 0)
			(layers "F.Cu" "F.Mask" "F.Paste")
			(net "PVCCIN_CPU0_VREF")
		)
	)
	(footprint ""
		(layer "F.Cu")
		(at 394.18641 -408.517344 -90)
		(property "Reference" "C884"
			(at 0 0 270)
			(layer "F.SilkS")
			(hide yes)
			(effects
				(font
					(size 1.27 1.27)
				)
			)
		)
		(property "Value" ""
			(at 0 0 270)
			(layer "F.Fab")
			(effects
				(font
					(size 1.27 1.27)
				)
			)
		)
		(duplicate_pad_numbers_are_jumpers no)
		(fp_line
			(start -0.299974 0.150114)
			(end -0.299974 -0.150114)
			(stroke
				(width 0.1)
				(type default)
			)
			(layer "F.Fab")
		)
		(fp_line
			(start 0.299974 0.150114)
			(end -0.299974 0.150114)
			(stroke
				(width 0.1)
				(type default)
			)
			(layer "F.Fab")
		)
		(fp_line
			(start -0.299974 -0.150114)
			(end 0.299974 -0.150114)
			(stroke
				(width 0.1)
				(type default)
			)
			(layer "F.Fab")
		)
		(fp_line
			(start 0.299974 -0.150114)
			(end 0.299974 0.150114)
			(stroke
				(width 0.1)
				(type default)
			)
			(layer "F.Fab")
		)
		(pad "1" smd rect
			(at -0.2667 0 270)
			(size 0.3048 0.381)
			(layers "F.Cu" "F.Mask" "F.Paste")
			(net "P5E_CPU0_PE3_TX_C_DN<8>")
		)
		(pad "2" smd rect
			(at 0.2667 0 270)
			(size 0.3048 0.381)
			(layers "F.Cu" "F.Mask" "F.Paste")
			(net "P5E_CPU0_PE3_TX_DN<8>")
		)
	)
)
